# SCM (Grand Teton) — schematic netlist excerpt (pin names and nets, part order shuffled) for the footprints in the layout excerpt that follows; sources: Cadence DE-HDL packaged netlist, KiCad conversion of 12092022_DA0F0TMDCD0_F0T_Management_Board_D_brd_V3_OCP.brd

R769  Q_RES  33.2 1% CHIP  pkg 0402LF  page 35 : A = FM_THROTTLE_N ; B = FM_THROTTLE_R_N
PC223  Q_CAP  0.1UF 25V 10% X7R  pkg 0402  page 52 : A = SW_P3V3_AUX_FLT ; B = GND

(kicad_pcb
	(version 20260206)
	(generator "pcbnew")
	(generator_version "10.0")
	(general
		(thickness 1.6)
		(legacy_teardrops no)
	)
	(paper "A4")
	(title_block
		(title "12092022_DA0F0TMDCD0_F0T_Management_Board_D_brd_V3_OCP.brd")
		(comment 1 "Grand Teton / footprints 398-399 of 1440")
	)
	(layers
		(0 "F.Cu" signal "TOP")
		(4 "In1.Cu" signal "GND")
		(6 "In2.Cu" signal "IN1")
		(8 "In3.Cu" signal "GND1")
		(10 "In4.Cu" signal "IN2")
		(12 "In5.Cu" signal "VCC")
		(14 "In6.Cu" signal "VCC1")
		(16 "In7.Cu" signal "IN3")
		(18 "In8.Cu" signal "GND2")
		(20 "In9.Cu" signal "IN4")
		(22 "In10.Cu" signal "GND3")
		(2 "B.Cu" signal "BOTTOM")
		(9 "F.Adhes" user "F.Adhesive")
		(11 "B.Adhes" user "B.Adhesive")
		(13 "F.Paste" user "Package Geometry/Pastemask Top")
		(15 "B.Paste" user "Package Geometry/Pastemask Bottom")
		(5 "F.SilkS" user "Ref Des/Silkscreen Top")
		(7 "B.SilkS" user "Ref Des/Silkscreen Bottom")
		(1 "F.Mask" user "Board Geometry/Soldermask Top")
		(3 "B.Mask" user "Board Geometry/Soldermask Bottom")
		(17 "Dwgs.User" user "User.Drawings")
		(19 "Cmts.User" user "User.Comments")
		(21 "Eco1.User" user "User.Eco1")
		(23 "Eco2.User" user "User.Eco2")
		(25 "Edge.Cuts" user "Board Geometry/Outline")
		(27 "Margin" user)
		(31 "F.CrtYd" user "Package Geometry/Place Bound Top")
		(29 "B.CrtYd" user "Package Geometry/Place Bound Bottom")
		(35 "F.Fab" user "Ref Des/Assembly Top")
		(33 "B.Fab" user "Ref Des/Assembly Bottom")
	)
	(footprint ""
		(layer "F.Cu")
		(at 30.2514 -101.0412 -90)
		(property "Reference" "R769"
			(at 0 0 270)
			(layer "F.SilkS")
			(hide yes)
			(effects
				(font
					(size 1.27 1.27)
				)
			)
		)
		(property "Value" ""
			(at 0 0 270)
			(layer "F.Fab")
			(effects
				(font
					(size 1.27 1.27)
				)
			)
		)
		(duplicate_pad_numbers_are_jumpers no)
		(fp_line
			(start -0.7874 0.4064)
			(end -0.7874 -0.4064)
			(stroke
				(width 0.1524)
				(type default)
			)
			(layer "F.SilkS")
		)
		(fp_line
			(start 0.7874 0.4064)
			(end -0.7874 0.4064)
			(stroke
				(width 0.1524)
				(type default)
			)
			(layer "F.SilkS")
		)
		(fp_line
			(start -0.7874 -0.4064)
			(end 0.7874 -0.4064)
			(stroke
				(width 0.1524)
				(type default)
			)
			(layer "F.SilkS")
		)
		(fp_line
			(start 0.7874 -0.4064)
			(end 0.7874 0.4064)
			(stroke
				(width 0.1524)
				(type default)
			)
			(layer "F.SilkS")
		)
		(fp_line
			(start -0.67945 0.3048)
			(end -0.67945 -0.305054)
			(stroke
				(width 0.1)
				(type default)
			)
			(layer "F.Fab")
		)
		(fp_line
			(start -0.12065 0.3048)
			(end -0.67945 0.3048)
			(stroke
				(width 0.1)
				(type default)
			)
			(layer "F.Fab")
		)
		(fp_line
			(start 0.120396 0.3048)
			(end 0.120396 0.2794)
			(stroke
				(width 0.1)
				(type default)
			)
			(layer "F.Fab")
		)
		(fp_line
			(start 0.67945 0.3048)
			(end 0.120396 0.3048)
			(stroke
				(width 0.1)
				(type default)
			)
			(layer "F.Fab")
		)
		(fp_line
			(start -0.12065 0.2794)
			(end -0.12065 0.3048)
			(stroke
				(width 0.1)
				(type default)
			)
			(layer "F.Fab")
		)
		(fp_line
			(start 0.120396 0.2794)
			(end -0.12065 0.2794)
			(stroke
				(width 0.1)
				(type default)
			)
			(layer "F.Fab")
		)
		(fp_line
			(start -0.12065 -0.2794)
			(end 0.12065 -0.2794)
			(stroke
				(width 0.1)
				(type default)
			)
			(layer "F.Fab")
		)
		(fp_line
			(start 0.12065 -0.2794)
			(end 0.12065 -0.3048)
			(stroke
				(width 0.1)
				(type default)
			)
			(layer "F.Fab")
		)
		(fp_line
			(start 0.12065 -0.3048)
			(end 0.67945 -0.3048)
			(stroke
				(width 0.1)
				(type default)
			)
			(layer "F.Fab")
		)
		(fp_line
			(start 0.67945 -0.3048)
			(end 0.67945 0.3048)
			(stroke
				(width 0.1)
				(type default)
			)
			(layer "F.Fab")
		)
		(fp_line
			(start -0.67945 -0.305054)
			(end -0.12065 -0.305054)
			(stroke
				(width 0.1)
				(type default)
			)
			(layer "F.Fab")
		)
		(fp_line
			(start -0.12065 -0.305054)
			(end -0.12065 -0.2794)
			(stroke
				(width 0.1)
				(type default)
			)
			(layer "F.Fab")
		)
		(pad "1" smd circle
			(at -0.40005 0 270)
			(size 0 0)
			(layers "F.Cu" "F.Mask" "F.Paste")
			(net "FM_THROTTLE_N")
		)
		(pad "2" smd circle
			(at 0.40005 0 270)
			(size 0 0)
			(layers "F.Cu" "F.Mask" "F.Paste")
			(net "FM_THROTTLE_R_N")
		)
	)
	(footprint ""
		(layer "F.Cu")
		(at 7.28091 -62.512702 180)
		(property "Reference" "PC223"
			(at 0 0 180)
			(layer "F.SilkS")
			(hide yes)
			(effects
				(font
					(size 1.27 1.27)
				)
			)
		)
		(property "Value" ""
			(at 0 0 180)
			(layer "F.Fab")
			(effects
				(font
					(size 1.27 1.27)
				)
			)
		)
		(duplicate_pad_numbers_are_jumpers no)
		(fp_line
			(start 0.7874 0.4064)
			(end -0.7874 0.4064)
			(stroke
				(width 0.1524)
				(type default)
			)
			(layer "F.SilkS")
		)
		(fp_line
			(start 0.7874 -0.4064)
			(end 0.7874 0.4064)
			(stroke
				(width 0.1524)
				(type default)
			)
			(layer "F.SilkS")
		)
		(fp_line
			(start -0.7874 0.4064)
			(end -0.7874 -0.4064)
			(stroke
				(width 0.1524)
				(type default)
			)
			(layer "F.SilkS")
		)
		(fp_line
			(start -0.7874 -0.4064)
			(end 0.7874 -0.4064)
			(stroke
				(width 0.1524)
				(type default)
			)
			(layer "F.SilkS")
		)
		(fp_line
			(start 0.67945 0.3048)
			(end 0.120396 0.3048)
			(stroke
				(width 0.1)
				(type default)
			)
			(layer "F.Fab")
		)
		(fp_line
			(start 0.67945 -0.3048)
			(end 0.67945 0.3048)
			(stroke
				(width 0.1)
				(type default)
			)
			(layer "F.Fab")
		)
		(fp_line
			(start 0.12065 -0.2794)
			(end 0.12065 -0.3048)
			(stroke
				(width 0.1)
				(type default)
			)
			(layer "F.Fab")
		)
		(fp_line
			(start 0.12065 -0.3048)
			(end 0.67945 -0.3048)
			(stroke
				(width 0.1)
				(type default)
			)
			(layer "F.Fab")
		)
		(fp_line
			(start 0.120396 0.3048)
			(end 0.120396 0.2794)
			(stroke
				(width 0.1)
				(type default)
			)
			(layer "F.Fab")
		)
		(fp_line
			(start 0.120396 0.2794)
			(end -0.12065 0.2794)
			(stroke
				(width 0.1)
				(type default)
			)
			(layer "F.Fab")
		)
		(fp_line
			(start -0.12065 0.3048)
			(end -0.67945 0.3048)
			(stroke
				(width 0.1)
				(type default)
			)
			(layer "F.Fab")
		)
		(fp_line
			(start -0.12065 0.2794)
			(end -0.12065 0.3048)
			(stroke
				(width 0.1)
				(type default)
			)
			(layer "F.Fab")
		)
		(fp_line
			(start -0.12065 -0.2794)
			(end 0.12065 -0.2794)
			(stroke
				(width 0.1)
				(type default)
			)
			(layer "F.Fab")
		)
		(fp_line
			(start -0.12065 -0.305054)
			(end -0.12065 -0.2794)
			(stroke
				(width 0.1)
				(type default)
			)
			(layer "F.Fab")
		)
		(fp_line
			(start -0.67945 0.3048)
			(end -0.67945 -0.305054)
			(stroke
				(width 0.1)
				(type default)
			)
			(layer "F.Fab")
		)
		(fp_line
			(start -0.67945 -0.305054)
			(end -0.12065 -0.305054)
			(stroke
				(width 0.1)
				(type default)
			)
			(layer "F.Fab")
		)
		(pad "1" smd circle
			(at -0.40005 0 180)
			(size 0 0)
			(layers "F.Cu" "F.Mask" "F.Paste")
			(net "SW_P3V3_AUX_FLT")
		)
		(pad "2" smd circle
			(at 0.40005 0 180)
			(size 0 0)
			(layers "F.Cu" "F.Mask" "F.Paste")
			(net "GND")
		)
	)
)
